(kicad_pcb
	(version 20241229)
	(generator "pcbnew")
	(generator_version "9.0")
	(general
		(thickness 1.6642)
		(legacy_teardrops no)
	)
	(paper "A3")
	(title_block
		(title "PolarFire SoM")
		(date "2025-07-22")
		(rev "1.1.4")
		(company "Antmicro Ltd")
		(comment 1 "www.antmicro.com")
		(comment 9 "footprint 383 of 470 (J1), pads 1-95 of 104")
	)
	(layers
		(0 "F.Cu" mixed)
		(4 "In1.Cu" power)
		(6 "In2.Cu" signal)
		(8 "In3.Cu" power)
		(10 "In4.Cu" signal)
		(12 "In5.Cu" power)
		(14 "In6.Cu" power)
		(16 "In7.Cu" signal)
		(18 "In8.Cu" power)
		(20 "In9.Cu" signal)
		(22 "In10.Cu" power)
		(24 "In11.Cu" signal)
		(26 "In12.Cu" signal)
		(2 "B.Cu" mixed)
		(9 "F.Adhes" user "F.Adhesive")
		(11 "B.Adhes" user "B.Adhesive")
		(13 "F.Paste" user)
		(15 "B.Paste" user)
		(5 "F.SilkS" user "F.Silkscreen")
		(7 "B.SilkS" user "B.Silkscreen")
		(1 "F.Mask" user)
		(3 "B.Mask" user)
		(17 "Dwgs.User" user "User.Drawings")
		(19 "Cmts.User" user "User.Comments")
		(21 "Eco1.User" user "User.Eco1")
		(23 "Eco2.User" user "User.Eco2")
		(25 "Edge.Cuts" user)
		(27 "Margin" user)
		(31 "F.CrtYd" user "F.Courtyard")
		(29 "B.CrtYd" user "B.Courtyard")
		(35 "F.Fab" user)
		(33 "B.Fab" user)
	)
	(footprint "antmicro-footprints:Conn_Plug_Hirose_DF40_2x50_DF40C-100DP-0.4V"
		(layer "B.Cu")
		(at 199.523 118.838 180)
		(property "Reference" "J1"
			(at -11.337 1.878 0)
			(layer "B.SilkS")
			(effects
				(font
					(size 0.7 0.7)
					(thickness 0.15)
				)
				(justify left bottom mirror)
			)
		)
		(property "Value" "Plug_Hirose_DF40_2x50_DF40C-100DP-0.4V"
			(at 0.001 -2.8 0)
			(layer "B.Fab")
			(hide yes)
			(effects
				(font
					(size 0.7 0.7)
					(thickness 0.15)
				)
				(justify left bottom mirror)
			)
		)
		(property "Datasheet" "https://www.hirose.com/en/product/document?clcode=CL0684-4032-1-51&productname=DF40C-100DP-0.4V(51)&series=DF40&documenttype=2DDrawing&lang=en&documentid=0001001212"
			(at 0 0 180)
			(layer "F.Fab")
			(hide yes)
			(effects
				(font
					(size 1.27 1.27)
					(thickness 0.15)
				)
			)
		)
		(property "Description" "Mezzanine Connector, Header, 0.4 mm, 2 Rows, 100 Contacts, Surface Mount, Phosphor Bronze"
			(at 0 0 180)
			(layer "F.Fab")
			(hide yes)
			(effects
				(font
					(size 1.27 1.27)
					(thickness 0.15)
				)
			)
		)
		(property "Author" "Antmicro"
			(at 399.046 237.676 0)
			(layer "B.Fab")
			(hide yes)
			(effects
				(font
					(size 1 1)
					(thickness 0.15)
				)
				(justify mirror)
			)
		)
		(property "License" "Apache-2.0"
			(at 399.046 237.676 0)
			(layer "B.Fab")
			(hide yes)
			(effects
				(font
					(size 1 1)
					(thickness 0.15)
				)
				(justify mirror)
			)
		)
		(property "MPN" "DF40C-100DP-0.4V(51)"
			(at 399.046 237.676 0)
			(layer "B.Fab")
			(hide yes)
			(effects
				(font
					(size 1 1)
					(thickness 0.15)
				)
				(justify mirror)
			)
		)
		(property "Manufacturer" "Hirose Electric"
			(at 399.046 237.676 0)
			(layer "B.Fab")
			(hide yes)
			(effects
				(font
					(size 1 1)
					(thickness 0.15)
				)
				(justify mirror)
			)
		)
		(property "Pitch" "0.4 mm"
			(at 399.046 237.676 0)
			(layer "B.Fab")
			(hide yes)
			(effects
				(font
					(size 1 1)
					(thickness 0.15)
				)
				(justify mirror)
			)
		)
		(sheetname "/Top Connector/")
		(sheetfile "top-connector.kicad_sch")
		(attr smd)
		(pad "1" smd rect
			(at -9.798 1.377 180)
			(size 0.23 0.66)
			(layers "B.Cu" "B.Mask" "B.Paste")
			(net 417 "GND")
			(pintype "passive")
		)
		(pad "2" smd rect
			(at -9.798 -1.333 180)
			(size 0.23 0.66)
			(layers "B.Cu" "B.Mask" "B.Paste")
			(net 417 "GND")
			(pintype "passive")
		)
		(pad "3" smd rect
			(at -9.399 1.377 180)
			(size 0.23 0.66)
			(layers "B.Cu" "B.Mask" "B.Paste")
			(net 70 "/Ethernet/ETH.TXRX_D_P")
			(pintype "passive")
		)
		(pad "4" smd rect
			(at -9.399 -1.333 180)
			(size 0.23 0.66)
			(layers "B.Cu" "B.Mask" "B.Paste")
			(net 71 "/Ethernet/ETH.TXRX_B_P")
			(pintype "passive")
		)
		(pad "5" smd rect
			(at -8.998 1.377 180)
			(size 0.23 0.66)
			(layers "B.Cu" "B.Mask" "B.Paste")
			(net 72 "/Ethernet/ETH.TXRX_D_N")
			(pintype "passive")
		)
		(pad "6" smd rect
			(at -8.998 -1.333 180)
			(size 0.23 0.66)
			(layers "B.Cu" "B.Mask" "B.Paste")
			(net 73 "/Ethernet/ETH.TXRX_B_N")
			(pintype "passive")
		)
		(pad "7" smd rect
			(at -8.598 1.377 180)
			(size 0.23 0.66)
			(layers "B.Cu" "B.Mask" "B.Paste")
			(net 417 "GND")
			(pintype "passive")
		)
		(pad "8" smd rect
			(at -8.598 -1.333 180)
			(size 0.23 0.66)
			(layers "B.Cu" "B.Mask" "B.Paste")
			(net 417 "GND")
			(pintype "passive")
		)
		(pad "9" smd rect
			(at -8.196 1.377 180)
			(size 0.23 0.66)
			(layers "B.Cu" "B.Mask" "B.Paste")
			(net 74 "/Ethernet/ETH.TXRX_C_N")
			(pintype "passive")
		)
		(pad "10" smd rect
			(at -8.196 -1.333 180)
			(size 0.23 0.66)
			(layers "B.Cu" "B.Mask" "B.Paste")
			(net 75 "/Ethernet/ETH.TXRX_A_N")
			(pintype "passive")
		)
		(pad "11" smd rect
			(at -7.798 1.377 180)
			(size 0.23 0.66)
			(layers "B.Cu" "B.Mask" "B.Paste")
			(net 76 "/Ethernet/ETH.TXRX_C_P")
			(pintype "passive")
		)
		(pad "12" smd rect
			(at -7.798 -1.333 180)
			(size 0.23 0.66)
			(layers "B.Cu" "B.Mask" "B.Paste")
			(net 77 "/Ethernet/ETH.TXRX_A_P")
			(pintype "passive")
		)
		(pad "13" smd rect
			(at -7.399 1.377 180)
			(size 0.23 0.66)
			(layers "B.Cu" "B.Mask" "B.Paste")
			(net 417 "GND")
			(pintype "passive")
		)
		(pad "14" smd rect
			(at -7.399 -1.333 180)
			(size 0.23 0.66)
			(layers "B.Cu" "B.Mask" "B.Paste")
			(net 417 "GND")
			(pintype "passive")
		)
		(pad "15" smd rect
			(at -6.998 1.377 180)
			(size 0.23 0.66)
			(layers "B.Cu" "B.Mask" "B.Paste")
			(net 78 "/Ethernet/ETH.LED2")
			(pintype "passive")
		)
		(pad "16" smd rect
			(at -6.998 -1.333 180)
			(size 0.23 0.66)
			(layers "B.Cu" "B.Mask" "B.Paste")
			(net 79 "/Ethernet/ETH.SYNC_IN")
			(pintype "passive")
		)
		(pad "17" smd rect
			(at -6.598 1.377 180)
			(size 0.23 0.66)
			(layers "B.Cu" "B.Mask" "B.Paste")
			(net 80 "/Ethernet/ETH.LED1")
			(pintype "passive")
		)
		(pad "18" smd rect
			(at -6.598 -1.333 180)
			(size 0.23 0.66)
			(layers "B.Cu" "B.Mask" "B.Paste")
			(net 81 "/Ethernet/ETH.SYNC_OUT")
			(pintype "passive")
		)
		(pad "19" smd rect
			(at -6.199 1.377 180)
			(size 0.23 0.66)
			(layers "B.Cu" "B.Mask" "B.Paste")
			(net 616 "unconnected-(J1-Pad19)")
			(pintype "passive+no_connect")
		)
		(pad "20" smd rect
			(at -6.199 -1.333 180)
			(size 0.23 0.66)
			(layers "B.Cu" "B.Mask" "B.Paste")
			(net 6 "unconnected-(J1-Pad20)")
			(pintype "passive+no_connect")
		)
		(pad "21" smd rect
			(at -5.798 1.377 180)
			(size 0.23 0.66)
			(layers "B.Cu" "B.Mask" "B.Paste")
			(net 7 "unconnected-(J1-Pad21)")
			(pintype "passive+no_connect")
		)
		(pad "22" smd rect
			(at -5.798 -1.333 180)
			(size 0.23 0.66)
			(layers "B.Cu" "B.Mask" "B.Paste")
			(net 417 "GND")
			(pintype "passive")
		)
		(pad "23" smd rect
			(at -5.399 1.377 180)
			(size 0.23 0.66)
			(layers "B.Cu" "B.Mask" "B.Paste")
			(net 417 "GND")
			(pintype "passive")
		)
		(pad "24" smd rect
			(at -5.399 -1.333 180)
			(size 0.23 0.66)
			(layers "B.Cu" "B.Mask" "B.Paste")
			(net 8 "GPIO26")
			(pintype "passive")
		)
		(pad "25" smd rect
			(at -4.998 1.377 180)
			(size 0.23 0.66)
			(layers "B.Cu" "B.Mask" "B.Paste")
			(net 20 "SPI6_SCLK{slash}RPI_GPIO21")
			(pintype "passive")
		)
		(pad "26" smd rect
			(at -4.998 -1.333 180)
			(size 0.23 0.66)
			(layers "B.Cu" "B.Mask" "B.Paste")
			(net 24 "SPI6_MISO{slash}RPI_GPIO19")
			(pintype "passive")
		)
		(pad "27" smd rect
			(at -4.598 1.377 180)
			(size 0.23 0.66)
			(layers "B.Cu" "B.Mask" "B.Paste")
			(net 25 "SPI6_MOSI{slash}RPI_GPIO20")
			(pintype "passive")
		)
		(pad "28" smd rect
			(at -4.598 -1.333 180)
			(size 0.23 0.66)
			(layers "B.Cu" "B.Mask" "B.Paste")
			(net 27 "UART5_TX{slash}RPI_GPIO13")
			(pintype "passive")
		)
		(pad "29" smd rect
			(at -4.199 1.377 180)
			(size 0.23 0.66)
			(layers "B.Cu" "B.Mask" "B.Paste")
			(net 11 "GPIO16")
			(pintype "passive")
		)
		(pad "30" smd rect
			(at -4.199 -1.333 180)
			(size 0.23 0.66)
			(layers "B.Cu" "B.Mask" "B.Paste")
			(net 12 "GPIO6")
			(pintype "passive")
		)
		(pad "31" smd rect
			(at -3.798 1.377 180)
			(size 0.23 0.66)
			(layers "B.Cu" "B.Mask" "B.Paste")
			(net 29 "UART5_TX{slash}RPI_GPIO12")
			(pintype "passive")
		)
		(pad "32" smd rect
			(at -3.798 -1.333 180)
			(size 0.23 0.66)
			(layers "B.Cu" "B.Mask" "B.Paste")
			(net 417 "GND")
			(pintype "passive")
		)
		(pad "33" smd rect
			(at -3.397 1.377 180)
			(size 0.23 0.66)
			(layers "B.Cu" "B.Mask" "B.Paste")
			(net 417 "GND")
			(pintype "passive")
		)
		(pad "34" smd rect
			(at -3.397 -1.333 180)
			(size 0.23 0.66)
			(layers "B.Cu" "B.Mask" "B.Paste")
			(net 30 "UART3_RX{slash}RPI_GPIO05")
			(pintype "passive")
		)
		(pad "35" smd rect
			(at -2.998 1.377 180)
			(size 0.23 0.66)
			(layers "B.Cu" "B.Mask" "B.Paste")
			(net 94 "/FPGA MSSIO/ID.SCL")
			(pintype "passive")
		)
		(pad "36" smd rect
			(at -2.998 -1.333 180)
			(size 0.23 0.66)
			(layers "B.Cu" "B.Mask" "B.Paste")
			(net 101 "/FPGA MSSIO/ID.SDA")
			(pintype "passive")
		)
		(pad "37" smd rect
			(at -2.597 1.377 180)
			(size 0.23 0.66)
			(layers "B.Cu" "B.Mask" "B.Paste")
			(net 17 "GPIO7")
			(pintype "passive")
		)
		(pad "38" smd rect
			(at -2.597 -1.333 180)
			(size 0.23 0.66)
			(layers "B.Cu" "B.Mask" "B.Paste")
			(net 18 "GPIO11")
			(pintype "passive")
		)
		(pad "39" smd rect
			(at -2.199 1.377 180)
			(size 0.23 0.66)
			(layers "B.Cu" "B.Mask" "B.Paste")
			(net 31 "UART4_TX{slash}RPI_GPIO08")
			(pintype "passive")
		)
		(pad "40" smd rect
			(at -2.199 -1.333 180)
			(size 0.23 0.66)
			(layers "B.Cu" "B.Mask" "B.Paste")
			(net 32 "UART4_RX{slash}RPI_GPIO09")
			(pintype "passive")
		)
		(pad "41" smd rect
			(at -1.798 1.377 180)
			(size 0.23 0.66)
			(layers "B.Cu" "B.Mask" "B.Paste")
			(net 21 "GPIO25")
			(pintype "passive")
		)
		(pad "42" smd rect
			(at -1.798 -1.333 180)
			(size 0.23 0.66)
			(layers "B.Cu" "B.Mask" "B.Paste")
			(net 417 "GND")
			(pintype "passive")
		)
		(pad "43" smd rect
			(at -1.397 1.377 180)
			(size 0.23 0.66)
			(layers "B.Cu" "B.Mask" "B.Paste")
			(net 34 "Net-(J1-Pad43)")
			(pintype "passive")
		)
		(pad "44" smd rect
			(at -1.397 -1.333 180)
			(size 0.23 0.66)
			(layers "B.Cu" "B.Mask" "B.Paste")
			(net 22 "GPIO10")
			(pintype "passive")
		)
		(pad "45" smd rect
			(at -0.998 1.377 180)
			(size 0.23 0.66)
			(layers "B.Cu" "B.Mask" "B.Paste")
			(net 23 "GPIO24")
			(pintype "passive")
		)
		(pad "46" smd rect
			(at -0.998 -1.333 180)
			(size 0.23 0.66)
			(layers "B.Cu" "B.Mask" "B.Paste")
			(net 63 "SDA6{slash}RPI_GPIO22")
			(pintype "passive")
		)
		(pad "47" smd rect
			(at -0.597 1.377 180)
			(size 0.23 0.66)
			(layers "B.Cu" "B.Mask" "B.Paste")
			(net 132 "SCL6{slash}RPI_GPIO23")
			(pintype "passive")
		)
		(pad "48" smd rect
			(at -0.597 -1.333 180)
			(size 0.23 0.66)
			(layers "B.Cu" "B.Mask" "B.Paste")
			(net 26 "GPIO27")
			(pintype "passive")
		)
		(pad "49" smd rect
			(at -0.199 1.377 180)
			(size 0.23 0.66)
			(layers "B.Cu" "B.Mask" "B.Paste")
			(net 133 "SPI6_CEO_N{slash}RPI_GPIO18")
			(pintype "passive")
		)
		(pad "50" smd rect
			(at -0.199 -1.333 180)
			(size 0.23 0.66)
			(layers "B.Cu" "B.Mask" "B.Paste")
			(net 245 "Net-(J1-Pad50)")
			(pintype "passive")
		)
		(pad "51" smd rect
			(at 0.201 1.377 180)
			(size 0.23 0.66)
			(layers "B.Cu" "B.Mask" "B.Paste")
			(net 134 "UART0_RX{slash}RPI_GPIO15")
			(pintype "passive")
		)
		(pad "52" smd rect
			(at 0.201 -1.333 180)
			(size 0.23 0.66)
			(layers "B.Cu" "B.Mask" "B.Paste")
			(net 417 "GND")
			(pintype "passive")
		)
		(pad "53" smd rect
			(at 0.6 1.377 180)
			(size 0.23 0.66)
			(layers "B.Cu" "B.Mask" "B.Paste")
			(net 417 "GND")
			(pintype "passive")
		)
		(pad "54" smd rect
			(at 0.6 -1.333 180)
			(size 0.23 0.66)
			(layers "B.Cu" "B.Mask" "B.Paste")
			(net 135 "UART3_TX{slash}RPI_GPIO04")
			(pintype "passive")
		)
		(pad "55" smd rect
			(at 1 1.377 180)
			(size 0.23 0.66)
			(layers "B.Cu" "B.Mask" "B.Paste")
			(net 173 "UART0_TX{slash}RPI_GPIO14")
			(pintype "passive")
		)
		(pad "56" smd rect
			(at 1 -1.333 180)
			(size 0.23 0.66)
			(layers "B.Cu" "B.Mask" "B.Paste")
			(net 174 "SCL1{slash}RPI_GPIO03")
			(pintype "passive")
		)
		(pad "57" smd rect
			(at 1.402 1.377 180)
			(size 0.23 0.66)
			(layers "B.Cu" "B.Mask" "B.Paste")
			(net 278 "/FPGA MSSIO/SD.CLK")
			(pintype "passive")
		)
		(pad "58" smd rect
			(at 1.402 -1.333 180)
			(size 0.23 0.66)
			(layers "B.Cu" "B.Mask" "B.Paste")
			(net 177 "SDA1{slash}RPI_GPIO02")
			(pintype "passive")
		)
		(pad "59" smd rect
			(at 1.802 1.377 180)
			(size 0.23 0.66)
			(layers "B.Cu" "B.Mask" "B.Paste")
			(net 417 "GND")
			(pintype "passive")
		)
		(pad "60" smd rect
			(at 1.802 -1.333 180)
			(size 0.23 0.66)
			(layers "B.Cu" "B.Mask" "B.Paste")
			(net 417 "GND")
			(pintype "passive")
		)
		(pad "61" smd rect
			(at 2.203 1.377 180)
			(size 0.23 0.66)
			(layers "B.Cu" "B.Mask" "B.Paste")
			(net 266 "/FPGA MSSIO/SD.DAT3")
			(pintype "passive")
		)
		(pad "62" smd rect
			(at 2.203 -1.333 180)
			(size 0.23 0.66)
			(layers "B.Cu" "B.Mask" "B.Paste")
			(net 388 "/FPGA MSSIO/SD.CMD")
			(pintype "passive")
		)
		(pad "63" smd rect
			(at 2.601 1.377 180)
			(size 0.23 0.66)
			(layers "B.Cu" "B.Mask" "B.Paste")
			(net 267 "/FPGA MSSIO/SD.DAT0")
			(pintype "passive")
		)
		(pad "64" smd rect
			(at 2.601 -1.333 180)
			(size 0.23 0.66)
			(layers "B.Cu" "B.Mask" "B.Paste")
			(net 268 "/FPGA MSSIO/SD.DAT5")
			(pintype "passive")
		)
		(pad "65" smd rect
			(at 3.001 1.377 180)
			(size 0.23 0.66)
			(layers "B.Cu" "B.Mask" "B.Paste")
			(net 417 "GND")
			(pintype "passive")
		)
		(pad "66" smd rect
			(at 3.001 -1.333 180)
			(size 0.23 0.66)
			(layers "B.Cu" "B.Mask" "B.Paste")
			(net 417 "GND")
			(pintype "passive")
		)
		(pad "67" smd rect
			(at 3.401 1.377 180)
			(size 0.23 0.66)
			(layers "B.Cu" "B.Mask" "B.Paste")
			(net 273 "/FPGA MSSIO/SD.DAT1")
			(pintype "passive")
		)
		(pad "68" smd rect
			(at 3.401 -1.333 180)
			(size 0.23 0.66)
			(layers "B.Cu" "B.Mask" "B.Paste")
			(net 277 "/FPGA MSSIO/SD.DAT4")
			(pintype "passive")
		)
		(pad "69" smd rect
			(at 3.802 1.377 180)
			(size 0.23 0.66)
			(layers "B.Cu" "B.Mask" "B.Paste")
			(net 274 "/FPGA MSSIO/SD.DAT2")
			(pintype "passive")
		)
		(pad "70" smd rect
			(at 3.802 -1.333 180)
			(size 0.23 0.66)
			(layers "B.Cu" "B.Mask" "B.Paste")
			(net 269 "/FPGA MSSIO/SD.DAT7")
			(pintype "passive")
		)
		(pad "71" smd rect
			(at 4.202 1.377 180)
			(size 0.23 0.66)
			(layers "B.Cu" "B.Mask" "B.Paste")
			(net 417 "GND")
			(pintype "passive")
		)
		(pad "72" smd rect
			(at 4.202 -1.333 180)
			(size 0.23 0.66)
			(layers "B.Cu" "B.Mask" "B.Paste")
			(net 276 "/FPGA MSSIO/SD.DAT6")
			(pintype "passive")
		)
		(pad "73" smd rect
			(at 4.6 1.377 180)
			(size 0.23 0.66)
			(layers "B.Cu" "B.Mask" "B.Paste")
			(net 246 "SD_VDD_OVERRIDE")
			(pintype "passive")
		)
		(pad "74" smd rect
			(at 4.6 -1.333 180)
			(size 0.23 0.66)
			(layers "B.Cu" "B.Mask" "B.Paste")
			(net 417 "GND")
			(pintype "passive")
		)
		(pad "75" smd rect
			(at 5.001 1.377 180)
			(size 0.23 0.66)
			(layers "B.Cu" "B.Mask" "B.Paste")
			(net 44 "SD_PWR_ON")
			(pintype "passive")
		)
		(pad "76" smd rect
			(at 5.001 -1.333 180)
			(size 0.23 0.66)
			(layers "B.Cu" "B.Mask" "B.Paste")
			(net 45 "unconnected-(J1-Pad76)")
			(pintype "passive+no_connect")
		)
		(pad "77" smd rect
			(at 5.401 1.377 180)
			(size 0.23 0.66)
			(layers "B.Cu" "B.Mask" "B.Paste")
			(net 90 "+5V")
			(pintype "passive")
		)
		(pad "78" smd rect
			(at 5.401 -1.333 180)
			(size 0.23 0.66)
			(layers "B.Cu" "B.Mask" "B.Paste")
			(net 333 "GPIO_VREF")
			(pintype "passive")
		)
		(pad "79" smd rect
			(at 5.802 1.377 180)
			(size 0.23 0.66)
			(layers "B.Cu" "B.Mask" "B.Paste")
			(net 90 "+5V")
			(pintype "passive")
		)
		(pad "80" smd rect
			(at 5.802 -1.333 180)
			(size 0.23 0.66)
			(layers "B.Cu" "B.Mask" "B.Paste")
			(net 623 "/FPGA GPIO/I^{2}C0.SCL")
			(pintype "passive")
		)
		(pad "81" smd rect
			(at 6.202 1.377 180)
			(size 0.23 0.66)
			(layers "B.Cu" "B.Mask" "B.Paste")
			(net 90 "+5V")
			(pintype "passive")
		)
		(pad "82" smd rect
			(at 6.202 -1.333 180)
			(size 0.23 0.66)
			(layers "B.Cu" "B.Mask" "B.Paste")
			(net 619 "/FPGA GPIO/I^{2}C0.SDA")
			(pintype "passive")
		)
		(pad "83" smd rect
			(at 6.6 1.377 180)
			(size 0.23 0.66)
			(layers "B.Cu" "B.Mask" "B.Paste")
			(net 90 "+5V")
			(pintype "passive")
		)
		(pad "84" smd rect
			(at 6.6 -1.333 180)
			(size 0.23 0.66)
			(layers "B.Cu" "B.Mask" "B.Paste")
			(net 50 "+3V3")
			(pintype "passive")
		)
		(pad "85" smd rect
			(at 7 1.377 180)
			(size 0.23 0.66)
			(layers "B.Cu" "B.Mask" "B.Paste")
			(net 90 "+5V")
			(pintype "passive")
		)
		(pad "86" smd rect
			(at 7 -1.333 180)
			(size 0.23 0.66)
			(layers "B.Cu" "B.Mask" "B.Paste")
			(net 50 "+3V3")
			(pintype "passive")
		)
		(pad "87" smd rect
			(at 7.401 1.377 180)
			(size 0.23 0.66)
			(layers "B.Cu" "B.Mask" "B.Paste")
			(net 90 "+5V")
			(pintype "passive")
		)
		(pad "88" smd rect
			(at 7.401 -1.333 180)
			(size 0.23 0.66)
			(layers "B.Cu" "B.Mask" "B.Paste")
			(net 48 "+1V8")
			(pintype "passive")
		)
		(pad "89" smd rect
			(at 7.802 1.377 180)
			(size 0.23 0.66)
			(layers "B.Cu" "B.Mask" "B.Paste")
			(net 171 "WL_REG_ON")
			(pintype "passive")
		)
		(pad "90" smd rect
			(at 7.802 -1.333 180)
			(size 0.23 0.66)
			(layers "B.Cu" "B.Mask" "B.Paste")
			(net 48 "+1V8")
			(pintype "passive")
		)
		(pad "91" smd rect
			(at 8.2 1.377 180)
			(size 0.23 0.66)
			(layers "B.Cu" "B.Mask" "B.Paste")
			(net 172 "BT_REG_ON")
			(pintype "passive")
		)
		(pad "92" smd rect
			(at 8.2 -1.333 180)
			(size 0.23 0.66)
			(layers "B.Cu" "B.Mask" "B.Paste")
			(net 54 "unconnected-(J1-Pad92)")
			(pintype "passive+no_connect")
		)
		(pad "93" smd rect
			(at 8.6 1.377 180)
			(size 0.23 0.66)
			(layers "B.Cu" "B.Mask" "B.Paste")
			(net 55 "unconnected-(J1-Pad93)")
			(pintype "passive+no_connect")
		)
		(pad "94" smd rect
			(at 8.6 -1.333 180)
			(size 0.23 0.66)
			(layers "B.Cu" "B.Mask" "B.Paste")
			(net 56 "unconnected-(J1-Pad94)")
			(pintype "passive+no_connect")
		)
		(pad "95" smd rect
			(at 9 1.377 180)
			(size 0.23 0.66)
			(layers "B.Cu" "B.Mask" "B.Paste")
			(net 98 "/Top Connector/PI_LED_nPWR")
			(pintype "passive")
		)
	)
)
